(kicad_pcb
	(version 20260206)
	(generator "pcbnew")
	(generator_version "10.0")
	(general
		(thickness 1.6)
		(legacy_teardrops no)
	)
	(paper "A4")
	(title_block
		(title "01162023_DA0F0TEBIF0_F0T_Expander_BD_F_brd_V02_OCP.brd")
		(comment 1 "Grand Teton / footprints 4552-4558 of 9728")
	)
	(layers
		(0 "F.Cu" signal "TOP")
		(4 "In1.Cu" signal "GND")
		(6 "In2.Cu" signal "VCC")
		(8 "In3.Cu" signal "VCC1")
		(10 "In4.Cu" signal "GND1")
		(12 "In5.Cu" signal "IN1")
		(14 "In6.Cu" signal "GND2")
		(16 "In7.Cu" signal "IN2")
		(18 "In8.Cu" signal "GND3")
		(20 "In9.Cu" signal "IN3")
		(22 "In10.Cu" signal "GND4")
		(24 "In11.Cu" signal "IN4")
		(26 "In12.Cu" signal "GND5")
		(28 "In13.Cu" signal "IN5")
		(30 "In14.Cu" signal "GND6")
		(32 "In15.Cu" signal "IN6")
		(34 "In16.Cu" signal "GND7")
		(2 "B.Cu" signal "BOTTOM")
		(9 "F.Adhes" user "F.Adhesive")
		(11 "B.Adhes" user "B.Adhesive")
		(13 "F.Paste" user "Package Geometry/Pastemask Top")
		(15 "B.Paste" user "Package Geometry/Pastemask Bottom")
		(5 "F.SilkS" user "Ref Des/Silkscreen Top")
		(7 "B.SilkS" user "Ref Des/Silkscreen Bottom")
		(1 "F.Mask" user "Board Geometry/Soldermask Top")
		(3 "B.Mask" user "Board Geometry/Soldermask Bottom")
		(17 "Dwgs.User" user "User.Drawings")
		(19 "Cmts.User" user "User.Comments")
		(21 "Eco1.User" user "User.Eco1")
		(23 "Eco2.User" user "User.Eco2")
		(25 "Edge.Cuts" user "Board Geometry/Outline")
		(27 "Margin" user)
		(31 "F.CrtYd" user "Package Geometry/Place Bound Top")
		(29 "B.CrtYd" user "Package Geometry/Place Bound Bottom")
		(35 "F.Fab" user "Ref Des/Assembly Top")
		(33 "B.Fab" user "Ref Des/Assembly Bottom")
	)
	(footprint ""
		(layer "F.Cu")
		(at 359.837736 -384.339846 -90)
		(property "Reference" "R6712"
			(at 0 0 270)
			(layer "F.SilkS")
			(hide yes)
			(effects
				(font
					(size 1.27 1.27)
				)
			)
		)
		(property "Value" ""
			(at 0 0 270)
			(layer "F.Fab")
			(effects
				(font
					(size 1.27 1.27)
				)
			)
		)
		(duplicate_pad_numbers_are_jumpers no)
		(fp_line
			(start -0.7874 0.4064)
			(end -0.7874 -0.4064)
			(stroke
				(width 0.1524)
				(type default)
			)
			(layer "F.SilkS")
		)
		(fp_line
			(start 0.7874 0.4064)
			(end -0.7874 0.4064)
			(stroke
				(width 0.1524)
				(type default)
			)
			(layer "F.SilkS")
		)
		(fp_line
			(start -0.7874 -0.4064)
			(end 0.7874 -0.4064)
			(stroke
				(width 0.1524)
				(type default)
			)
			(layer "F.SilkS")
		)
		(fp_line
			(start 0.7874 -0.4064)
			(end 0.7874 0.4064)
			(stroke
				(width 0.1524)
				(type default)
			)
			(layer "F.SilkS")
		)
		(fp_line
			(start -0.67945 0.3048)
			(end -0.67945 -0.305054)
			(stroke
				(width 0.1)
				(type default)
			)
			(layer "F.Fab")
		)
		(fp_line
			(start -0.12065 0.3048)
			(end -0.67945 0.3048)
			(stroke
				(width 0.1)
				(type default)
			)
			(layer "F.Fab")
		)
		(fp_line
			(start 0.120396 0.3048)
			(end 0.120396 0.2794)
			(stroke
				(width 0.1)
				(type default)
			)
			(layer "F.Fab")
		)
		(fp_line
			(start 0.67945 0.3048)
			(end 0.120396 0.3048)
			(stroke
				(width 0.1)
				(type default)
			)
			(layer "F.Fab")
		)
		(fp_line
			(start -0.12065 0.2794)
			(end -0.12065 0.3048)
			(stroke
				(width 0.1)
				(type default)
			)
			(layer "F.Fab")
		)
		(fp_line
			(start 0.120396 0.2794)
			(end -0.12065 0.2794)
			(stroke
				(width 0.1)
				(type default)
			)
			(layer "F.Fab")
		)
		(fp_line
			(start -0.12065 -0.2794)
			(end 0.12065 -0.2794)
			(stroke
				(width 0.1)
				(type default)
			)
			(layer "F.Fab")
		)
		(fp_line
			(start 0.12065 -0.2794)
			(end 0.12065 -0.3048)
			(stroke
				(width 0.1)
				(type default)
			)
			(layer "F.Fab")
		)
		(fp_line
			(start 0.12065 -0.3048)
			(end 0.67945 -0.3048)
			(stroke
				(width 0.1)
				(type default)
			)
			(layer "F.Fab")
		)
		(fp_line
			(start 0.67945 -0.3048)
			(end 0.67945 0.3048)
			(stroke
				(width 0.1)
				(type default)
			)
			(layer "F.Fab")
		)
		(fp_line
			(start -0.67945 -0.305054)
			(end -0.12065 -0.305054)
			(stroke
				(width 0.1)
				(type default)
			)
			(layer "F.Fab")
		)
		(fp_line
			(start -0.12065 -0.305054)
			(end -0.12065 -0.2794)
			(stroke
				(width 0.1)
				(type default)
			)
			(layer "F.Fab")
		)
		(pad "1" smd circle
			(at -0.40005 0 270)
			(size 0 0)
			(layers "F.Cu" "F.Mask" "F.Paste")
			(net "MB_3V3IO_RSVD4_ISO")
		)
		(pad "2" smd circle
			(at 0.40005 0 270)
			(size 0 0)
			(layers "F.Cu" "F.Mask" "F.Paste")
			(net "MB_3V3IO_RSVD4")
		)
	)
	(footprint ""
		(layer "F.Cu")
		(at 5.589524 -68.64223)
		(property "Reference" "Q133"
			(at -2.823718 -2.09042 0)
			(unlocked yes)
			(layer "F.SilkS")
			(effects
				(font
					(size 0.7874 0.5842)
					(thickness 0.1524)
				)
			)
		)
		(property "Value" ""
			(at 0 0 0)
			(layer "F.Fab")
			(effects
				(font
					(size 1.27 1.27)
				)
			)
		)
		(duplicate_pad_numbers_are_jumpers no)
		(fp_line
			(start -1.376172 -1.199896)
			(end -0.508 -1.199896)
			(stroke
				(width 0.1524)
				(type default)
			)
			(layer "F.SilkS")
		)
		(fp_line
			(start -1.376172 1.199896)
			(end -1.376172 -1.199896)
			(stroke
				(width 0.1524)
				(type default)
			)
			(layer "F.SilkS")
		)
		(fp_line
			(start -0.508 -1.199896)
			(end 0 -0.762)
			(stroke
				(width 0.1524)
				(type default)
			)
			(layer "F.SilkS")
		)
		(fp_line
			(start 0 -0.762)
			(end 0.508 -1.199896)
			(stroke
				(width 0.1524)
				(type default)
			)
			(layer "F.SilkS")
		)
		(fp_line
			(start 0.508 -1.199896)
			(end 1.376172 -1.199896)
			(stroke
				(width 0.1524)
				(type default)
			)
			(layer "F.SilkS")
		)
		(fp_line
			(start 1.376172 -1.199896)
			(end 1.376172 1.199896)
			(stroke
				(width 0.1524)
				(type default)
			)
			(layer "F.SilkS")
		)
		(fp_line
			(start 1.376172 1.199896)
			(end -1.376172 1.199896)
			(stroke
				(width 0.1524)
				(type default)
			)
			(layer "F.SilkS")
		)
		(fp_poly
			(pts
				(xy -1.352804 -0.832866) (xy -1.622044 -1.641094) (xy -2.161032 -1.10236)
			)
			(stroke
				(width 0)
				(type default)
			)
			(fill yes)
			(layer "F.SilkS")
		)
		(fp_line
			(start -0.674878 -1.100074)
			(end 0.674878 -1.100074)
			(stroke
				(width 0.1)
				(type default)
			)
			(layer "F.Fab")
		)
		(fp_line
			(start -0.674878 1.100074)
			(end -0.674878 -1.100074)
			(stroke
				(width 0.1)
				(type default)
			)
			(layer "F.Fab")
		)
		(fp_line
			(start 0.674878 -1.100074)
			(end 0.674878 1.100074)
			(stroke
				(width 0.1)
				(type default)
			)
			(layer "F.Fab")
		)
		(fp_line
			(start 0.674878 1.100074)
			(end -0.674878 1.100074)
			(stroke
				(width 0.1)
				(type default)
			)
			(layer "F.Fab")
		)
		(fp_poly
			(pts
				(xy -1.4605 -0.7493) (xy -2.2225 -1.1303) (xy -2.2225 -0.3683)
			)
			(stroke
				(width 0)
				(type default)
			)
			(fill yes)
			(layer "F.Fab")
		)
		(pad "1" smd rect
			(at -0.899922 -0.750062 270)
			(size 0.6096 0.6096)
			(layers "F.Cu" "F.Mask" "F.Paste")
			(net "GND")
		)
		(pad "2" smd rect
			(at -0.899922 0 270)
			(size 0.4064 0.6096)
			(layers "F.Cu" "F.Mask" "F.Paste")
			(net "P3V3_SSD0_PG_G1")
		)
		(pad "3" smd rect
			(at -0.899922 0.750062 270)
			(size 0.6096 0.6096)
			(layers "F.Cu" "F.Mask" "F.Paste")
			(net "PWRGD_P3V3_SSD0_D")
		)
		(pad "4" smd rect
			(at 0.899922 0.750062 270)
			(size 0.6096 0.6096)
			(layers "F.Cu" "F.Mask" "F.Paste")
			(net "GND")
		)
		(pad "5" smd rect
			(at 0.899922 0 270)
			(size 0.4064 0.6096)
			(layers "F.Cu" "F.Mask" "F.Paste")
			(net "P3V3_SSD0_PG_G2")
		)
		(pad "6" smd rect
			(at 0.899922 -0.750062 270)
			(size 0.6096 0.6096)
			(layers "F.Cu" "F.Mask" "F.Paste")
			(net "P3V3_SSD0_PG_G2")
		)
	)
	(footprint ""
		(layer "F.Cu")
		(at 378.382022 -292.991032 180)
		(property "Reference" "C3554"
			(at 0 0 180)
			(layer "F.SilkS")
			(hide yes)
			(effects
				(font
					(size 1.27 1.27)
				)
			)
		)
		(property "Value" ""
			(at 0 0 180)
			(layer "F.Fab")
			(effects
				(font
					(size 1.27 1.27)
				)
			)
		)
		(duplicate_pad_numbers_are_jumpers no)
		(fp_line
			(start 1.2954 0.5842)
			(end -1.2954 0.5842)
			(stroke
				(width 0.1524)
				(type default)
			)
			(layer "F.SilkS")
		)
		(fp_line
			(start 1.2954 -0.5842)
			(end 1.2954 0.5842)
			(stroke
				(width 0.1524)
				(type default)
			)
			(layer "F.SilkS")
		)
		(fp_line
			(start -1.2954 0.5842)
			(end -1.2954 -0.5842)
			(stroke
				(width 0.1524)
				(type default)
			)
			(layer "F.SilkS")
		)
		(fp_line
			(start -1.2954 -0.5842)
			(end 1.2954 -0.5842)
			(stroke
				(width 0.1524)
				(type default)
			)
			(layer "F.SilkS")
		)
		(fp_line
			(start 1.1938 0.4064)
			(end 0.8636 0.4064)
			(stroke
				(width 0.1)
				(type default)
			)
			(layer "F.Fab")
		)
		(fp_line
			(start 1.1938 -0.4064)
			(end 1.1938 0.4064)
			(stroke
				(width 0.1)
				(type default)
			)
			(layer "F.Fab")
		)
		(fp_line
			(start 0.8636 0.4572)
			(end -0.8636 0.4572)
			(stroke
				(width 0.1)
				(type default)
			)
			(layer "F.Fab")
		)
		(fp_line
			(start 0.8636 0.4064)
			(end 0.8636 0.4572)
			(stroke
				(width 0.1)
				(type default)
			)
			(layer "F.Fab")
		)
		(fp_line
			(start 0.8636 -0.4064)
			(end 1.1938 -0.4064)
			(stroke
				(width 0.1)
				(type default)
			)
			(layer "F.Fab")
		)
		(fp_line
			(start 0.8636 -0.4572)
			(end 0.8636 -0.4064)
			(stroke
				(width 0.1)
				(type default)
			)
			(layer "F.Fab")
		)
		(fp_line
			(start -0.8636 0.4572)
			(end -0.8636 0.4064)
			(stroke
				(width 0.1)
				(type default)
			)
			(layer "F.Fab")
		)
		(fp_line
			(start -0.8636 0.4064)
			(end -1.1938 0.4064)
			(stroke
				(width 0.1)
				(type default)
			)
			(layer "F.Fab")
		)
		(fp_line
			(start -0.8636 -0.4064)
			(end -0.8636 -0.4572)
			(stroke
				(width 0.1)
				(type default)
			)
			(layer "F.Fab")
		)
		(fp_line
			(start -0.8636 -0.4572)
			(end 0.8636 -0.4572)
			(stroke
				(width 0.1)
				(type default)
			)
			(layer "F.Fab")
		)
		(fp_line
			(start -1.1938 0.4064)
			(end -1.1938 -0.4064)
			(stroke
				(width 0.1)
				(type default)
			)
			(layer "F.Fab")
		)
		(fp_line
			(start -1.1938 -0.4064)
			(end -0.8636 -0.4064)
			(stroke
				(width 0.1)
				(type default)
			)
			(layer "F.Fab")
		)
		(pad "1" smd rect
			(at -0.7366 0 90)
			(size 0.7112 0.8128)
			(layers "F.Cu" "F.Mask" "F.Paste")
			(net "PCEPLL2_VDDA18_PEX3_R")
		)
		(pad "2" smd rect
			(at 0.7366 0 90)
			(size 0.7112 0.8128)
			(layers "F.Cu" "F.Mask" "F.Paste")
			(net "GND")
		)
	)
	(footprint ""
		(layer "F.Cu")
		(at 31.454344 -252.356874 -90)
		(property "Reference" "R1195"
			(at 0 0 270)
			(layer "F.SilkS")
			(hide yes)
			(effects
				(font
					(size 1.27 1.27)
				)
			)
		)
		(property "Value" ""
			(at 0 0 270)
			(layer "F.Fab")
			(effects
				(font
					(size 1.27 1.27)
				)
			)
		)
		(duplicate_pad_numbers_are_jumpers no)
		(fp_line
			(start -0.7874 0.4064)
			(end -0.7874 -0.4064)
			(stroke
				(width 0.1524)
				(type default)
			)
			(layer "F.SilkS")
		)
		(fp_line
			(start 0.7874 0.4064)
			(end -0.7874 0.4064)
			(stroke
				(width 0.1524)
				(type default)
			)
			(layer "F.SilkS")
		)
		(fp_line
			(start -0.7874 -0.4064)
			(end 0.7874 -0.4064)
			(stroke
				(width 0.1524)
				(type default)
			)
			(layer "F.SilkS")
		)
		(fp_line
			(start 0.7874 -0.4064)
			(end 0.7874 0.4064)
			(stroke
				(width 0.1524)
				(type default)
			)
			(layer "F.SilkS")
		)
		(fp_line
			(start -0.67945 0.3048)
			(end -0.67945 -0.305054)
			(stroke
				(width 0.1)
				(type default)
			)
			(layer "F.Fab")
		)
		(fp_line
			(start -0.12065 0.3048)
			(end -0.67945 0.3048)
			(stroke
				(width 0.1)
				(type default)
			)
			(layer "F.Fab")
		)
		(fp_line
			(start 0.120396 0.3048)
			(end 0.120396 0.2794)
			(stroke
				(width 0.1)
				(type default)
			)
			(layer "F.Fab")
		)
		(fp_line
			(start 0.67945 0.3048)
			(end 0.120396 0.3048)
			(stroke
				(width 0.1)
				(type default)
			)
			(layer "F.Fab")
		)
		(fp_line
			(start -0.12065 0.2794)
			(end -0.12065 0.3048)
			(stroke
				(width 0.1)
				(type default)
			)
			(layer "F.Fab")
		)
		(fp_line
			(start 0.120396 0.2794)
			(end -0.12065 0.2794)
			(stroke
				(width 0.1)
				(type default)
			)
			(layer "F.Fab")
		)
		(fp_line
			(start -0.12065 -0.2794)
			(end 0.12065 -0.2794)
			(stroke
				(width 0.1)
				(type default)
			)
			(layer "F.Fab")
		)
		(fp_line
			(start 0.12065 -0.2794)
			(end 0.12065 -0.3048)
			(stroke
				(width 0.1)
				(type default)
			)
			(layer "F.Fab")
		)
		(fp_line
			(start 0.12065 -0.3048)
			(end 0.67945 -0.3048)
			(stroke
				(width 0.1)
				(type default)
			)
			(layer "F.Fab")
		)
		(fp_line
			(start 0.67945 -0.3048)
			(end 0.67945 0.3048)
			(stroke
				(width 0.1)
				(type default)
			)
			(layer "F.Fab")
		)
		(fp_line
			(start -0.67945 -0.305054)
			(end -0.12065 -0.305054)
			(stroke
				(width 0.1)
				(type default)
			)
			(layer "F.Fab")
		)
		(fp_line
			(start -0.12065 -0.305054)
			(end -0.12065 -0.2794)
			(stroke
				(width 0.1)
				(type default)
			)
			(layer "F.Fab")
		)
		(pad "1" smd circle
			(at -0.40005 0 270)
			(size 0 0)
			(layers "F.Cu" "F.Mask" "F.Paste")
			(net "GND")
		)
		(pad "2" smd circle
			(at 0.40005 0 270)
			(size 0 0)
			(layers "F.Cu" "F.Mask" "F.Paste")
			(net "PEX0_MODE_SEL4")
		)
	)
	(footprint ""
		(layer "F.Cu")
		(at 456.62088 -254.5969 -90)
		(property "Reference" "C4397"
			(at 0 0 270)
			(layer "F.SilkS")
			(hide yes)
			(effects
				(font
					(size 1.27 1.27)
				)
			)
		)
		(property "Value" ""
			(at 0 0 270)
			(layer "F.Fab")
			(effects
				(font
					(size 1.27 1.27)
				)
			)
		)
		(duplicate_pad_numbers_are_jumpers no)
		(fp_line
			(start -1.2954 0.5842)
			(end -1.2954 -0.5842)
			(stroke
				(width 0.1524)
				(type default)
			)
			(layer "F.SilkS")
		)
		(fp_line
			(start 1.2954 0.5842)
			(end -1.2954 0.5842)
			(stroke
				(width 0.1524)
				(type default)
			)
			(layer "F.SilkS")
		)
		(fp_line
			(start -1.2954 -0.5842)
			(end 1.2954 -0.5842)
			(stroke
				(width 0.1524)
				(type default)
			)
			(layer "F.SilkS")
		)
		(fp_line
			(start 1.2954 -0.5842)
			(end 1.2954 0.5842)
			(stroke
				(width 0.1524)
				(type default)
			)
			(layer "F.SilkS")
		)
		(fp_line
			(start -0.8636 0.4572)
			(end -0.8636 0.4064)
			(stroke
				(width 0.1)
				(type default)
			)
			(layer "F.Fab")
		)
		(fp_line
			(start 0.8636 0.4572)
			(end -0.8636 0.4572)
			(stroke
				(width 0.1)
				(type default)
			)
			(layer "F.Fab")
		)
		(fp_line
			(start -1.1938 0.4064)
			(end -1.1938 -0.4064)
			(stroke
				(width 0.1)
				(type default)
			)
			(layer "F.Fab")
		)
		(fp_line
			(start -0.8636 0.4064)
			(end -1.1938 0.4064)
			(stroke
				(width 0.1)
				(type default)
			)
			(layer "F.Fab")
		)
		(fp_line
			(start 0.8636 0.4064)
			(end 0.8636 0.4572)
			(stroke
				(width 0.1)
				(type default)
			)
			(layer "F.Fab")
		)
		(fp_line
			(start 1.1938 0.4064)
			(end 0.8636 0.4064)
			(stroke
				(width 0.1)
				(type default)
			)
			(layer "F.Fab")
		)
		(fp_line
			(start -1.1938 -0.4064)
			(end -0.8636 -0.4064)
			(stroke
				(width 0.1)
				(type default)
			)
			(layer "F.Fab")
		)
		(fp_line
			(start -0.8636 -0.4064)
			(end -0.8636 -0.4572)
			(stroke
				(width 0.1)
				(type default)
			)
			(layer "F.Fab")
		)
		(fp_line
			(start 0.8636 -0.4064)
			(end 1.1938 -0.4064)
			(stroke
				(width 0.1)
				(type default)
			)
			(layer "F.Fab")
		)
		(fp_line
			(start 1.1938 -0.4064)
			(end 1.1938 0.4064)
			(stroke
				(width 0.1)
				(type default)
			)
			(layer "F.Fab")
		)
		(fp_line
			(start -0.8636 -0.4572)
			(end 0.8636 -0.4572)
			(stroke
				(width 0.1)
				(type default)
			)
			(layer "F.Fab")
		)
		(fp_line
			(start 0.8636 -0.4572)
			(end 0.8636 -0.4064)
			(stroke
				(width 0.1)
				(type default)
			)
			(layer "F.Fab")
		)
		(pad "1" smd rect
			(at -0.7366 0 180)
			(size 0.7112 0.8128)
			(layers "F.Cu" "F.Mask" "F.Paste")
			(net "P1V25_SERDES_VDDPLL_PEX3_C3")
		)
		(pad "2" smd rect
			(at 0.7366 0 180)
			(size 0.7112 0.8128)
			(layers "F.Cu" "F.Mask" "F.Paste")
			(net "GND")
		)
	)
	(footprint ""
		(layer "F.Cu")
		(at 439.334148 -306.074572 90)
		(property "Reference" "R1442"
			(at 0 0 90)
			(layer "F.SilkS")
			(hide yes)
			(effects
				(font
					(size 1.27 1.27)
				)
			)
		)
		(property "Value" ""
			(at 0 0 90)
			(layer "F.Fab")
			(effects
				(font
					(size 1.27 1.27)
				)
			)
		)
		(duplicate_pad_numbers_are_jumpers no)
		(fp_line
			(start 0.7874 -0.4064)
			(end 0.7874 0.4064)
			(stroke
				(width 0.1524)
				(type default)
			)
			(layer "F.SilkS")
		)
		(fp_line
			(start -0.7874 -0.4064)
			(end 0.7874 -0.4064)
			(stroke
				(width 0.1524)
				(type default)
			)
			(layer "F.SilkS")
		)
		(fp_line
			(start 0.7874 0.4064)
			(end -0.7874 0.4064)
			(stroke
				(width 0.1524)
				(type default)
			)
			(layer "F.SilkS")
		)
		(fp_line
			(start -0.7874 0.4064)
			(end -0.7874 -0.4064)
			(stroke
				(width 0.1524)
				(type default)
			)
			(layer "F.SilkS")
		)
		(fp_line
			(start -0.12065 -0.305054)
			(end -0.12065 -0.2794)
			(stroke
				(width 0.1)
				(type default)
			)
			(layer "F.Fab")
		)
		(fp_line
			(start -0.67945 -0.305054)
			(end -0.12065 -0.305054)
			(stroke
				(width 0.1)
				(type default)
			)
			(layer "F.Fab")
		)
		(fp_line
			(start 0.67945 -0.3048)
			(end 0.67945 0.3048)
			(stroke
				(width 0.1)
				(type default)
			)
			(layer "F.Fab")
		)
		(fp_line
			(start 0.12065 -0.3048)
			(end 0.67945 -0.3048)
			(stroke
				(width 0.1)
				(type default)
			)
			(layer "F.Fab")
		)
		(fp_line
			(start 0.12065 -0.2794)
			(end 0.12065 -0.3048)
			(stroke
				(width 0.1)
				(type default)
			)
			(layer "F.Fab")
		)
		(fp_line
			(start -0.12065 -0.2794)
			(end 0.12065 -0.2794)
			(stroke
				(width 0.1)
				(type default)
			)
			(layer "F.Fab")
		)
		(fp_line
			(start 0.120396 0.2794)
			(end -0.12065 0.2794)
			(stroke
				(width 0.1)
				(type default)
			)
			(layer "F.Fab")
		)
		(fp_line
			(start -0.12065 0.2794)
			(end -0.12065 0.3048)
			(stroke
				(width 0.1)
				(type default)
			)
			(layer "F.Fab")
		)
		(fp_line
			(start 0.67945 0.3048)
			(end 0.120396 0.3048)
			(stroke
				(width 0.1)
				(type default)
			)
			(layer "F.Fab")
		)
		(fp_line
			(start 0.120396 0.3048)
			(end 0.120396 0.2794)
			(stroke
				(width 0.1)
				(type default)
			)
			(layer "F.Fab")
		)
		(fp_line
			(start -0.12065 0.3048)
			(end -0.67945 0.3048)
			(stroke
				(width 0.1)
				(type default)
			)
			(layer "F.Fab")
		)
		(fp_line
			(start -0.67945 0.3048)
			(end -0.67945 -0.305054)
			(stroke
				(width 0.1)
				(type default)
			)
			(layer "F.Fab")
		)
		(pad "1" smd circle
			(at -0.40005 0 90)
			(size 0 0)
			(layers "F.Cu" "F.Mask" "F.Paste")
			(net "PEX3_SPARE1")
		)
		(pad "2" smd circle
			(at 0.40005 0 90)
			(size 0 0)
			(layers "F.Cu" "F.Mask" "F.Paste")
			(net "P1V8_PEX")
		)
	)
	(footprint ""
		(layer "F.Cu")
		(at 212.71992 -15.649956 180)
		(property "Reference" "H131"
			(at -1.44018 2.69621 0)
			(unlocked yes)
			(layer "B.SilkS")
			(effects
				(font
					(size 0.7874 0.5842)
					(thickness 0.1524)
				)
				(justify left mirror)
			)
		)
		(property "Value" ""
			(at 0 0 180)
			(layer "F.Fab")
			(effects
				(font
					(size 1.27 1.27)
				)
			)
		)
		(duplicate_pad_numbers_are_jumpers no)
		(pad "1" thru_hole rect
			(at 0 0 180)
			(size 4.2164 5.0038)
			(drill 2.0066
				(offset 0.099822 0)
			)
			(layers "*.Cu" "*.Mask")
			(remove_unused_layers no)
			(net "Net_8532")
			(clearance -0.8509)
			(padstack
				(mode front_inner_back)
				(layer "Inner"
					(shape circle)
					(size 4.0132 4.0132)
					(clearance -0.7493)
				)
				(layer "B.Cu"
					(shape circle)
					(size 4.0132 4.0132)
					(clearance -0.7493)
				)
			)
		)
	)
)
